# S9S_MB_2U (Grand Teton) — schematic netlist excerpt (pin names and nets, part order shuffled) for the footprints in the layout excerpt that follows; sources: Cadence DE-HDL packaged netlist, KiCad conversion of 03242023_DA0F0TMBIJ0_F0T_Motherboard_J_brd_V01_OCP.brd

R177  Q_RES  100 1% CHIP  pkg 0402LF  page 124 : A = PWRGD_DRAMPWRGD_CPU0_CD_LVC1_R2 ; B = PVCCD_HV_CPU0
R1484  Q_RES  1K 1% EMPTY  pkg 0402LF  page 208 : A = FM_CK440Q_DEV_25M_EN ; B = GND

(kicad_pcb
	(version 20260206)
	(generator "pcbnew")
	(generator_version "10.0")
	(general
		(thickness 1.6)
		(legacy_teardrops no)
	)
	(paper "A4")
	(title_block
		(title "03242023_DA0F0TMBIJ0_F0T_Motherboard_J_brd_V01_OCP.brd")
		(comment 1 "Grand Teton / footprints 5500-5501 of 6105")
	)
	(layers
		(0 "F.Cu" signal "TOP")
		(4 "In1.Cu" signal "GND")
		(6 "In2.Cu" signal "IN1")
		(8 "In3.Cu" signal "GND1")
		(10 "In4.Cu" signal "IN2")
		(12 "In5.Cu" signal "GND2")
		(14 "In6.Cu" signal "IN3")
		(16 "In7.Cu" signal "GND3")
		(18 "In8.Cu" signal "VCC")
		(20 "In9.Cu" signal "VCC1")
		(22 "In10.Cu" signal "GND4")
		(24 "In11.Cu" signal "IN4")
		(26 "In12.Cu" signal "GND5")
		(28 "In13.Cu" signal "IN5")
		(30 "In14.Cu" signal "GND6")
		(32 "In15.Cu" signal "IN6")
		(34 "In16.Cu" signal "GND7")
		(2 "B.Cu" signal "BOTTOM")
		(9 "F.Adhes" user "F.Adhesive")
		(11 "B.Adhes" user "B.Adhesive")
		(13 "F.Paste" user "Package Geometry/Pastemask Top")
		(15 "B.Paste" user "Package Geometry/Pastemask Bottom")
		(5 "F.SilkS" user "Ref Des/Silkscreen Top")
		(7 "B.SilkS" user "Ref Des/Silkscreen Bottom")
		(1 "F.Mask" user "Board Geometry/Soldermask Top")
		(3 "B.Mask" user "Board Geometry/Soldermask Bottom")
		(17 "Dwgs.User" user "User.Drawings")
		(19 "Cmts.User" user "User.Comments")
		(21 "Eco1.User" user "User.Eco1")
		(23 "Eco2.User" user "User.Eco2")
		(25 "Edge.Cuts" user "Board Geometry/Outline")
		(27 "Margin" user)
		(31 "F.CrtYd" user "Package Geometry/Place Bound Top")
		(29 "B.CrtYd" user "Package Geometry/Place Bound Bottom")
		(35 "F.Fab" user "Ref Des/Assembly Top")
		(33 "B.Fab" user "Ref Des/Assembly Bottom")
	)
	(footprint ""
		(layer "B.Cu")
		(at 299.129958 -193.67373 90)
		(property "Reference" "R177"
			(at 0 0 90)
			(layer "B.SilkS")
			(hide yes)
			(effects
				(font
					(size 1.27 1.27)
				)
				(justify mirror)
			)
		)
		(property "Value" ""
			(at 0 0 90)
			(layer "B.Fab")
			(effects
				(font
					(size 1.27 1.27)
				)
				(justify mirror)
			)
		)
		(duplicate_pad_numbers_are_jumpers no)
		(fp_line
			(start 0.7874 -0.4064)
			(end -0.7874 -0.4064)
			(stroke
				(width 0.1524)
				(type default)
			)
			(layer "B.SilkS")
		)
		(fp_line
			(start -0.7874 -0.4064)
			(end -0.7874 0.4064)
			(stroke
				(width 0.1524)
				(type default)
			)
			(layer "B.SilkS")
		)
		(fp_line
			(start 0.7874 0.4064)
			(end 0.7874 -0.4064)
			(stroke
				(width 0.1524)
				(type default)
			)
			(layer "B.SilkS")
		)
		(fp_line
			(start -0.7874 0.4064)
			(end 0.7874 0.4064)
			(stroke
				(width 0.1524)
				(type default)
			)
			(layer "B.SilkS")
		)
		(fp_line
			(start 0.67945 -0.305054)
			(end 0.12065 -0.305054)
			(stroke
				(width 0.1)
				(type default)
			)
			(layer "B.Fab")
		)
		(fp_line
			(start 0.12065 -0.305054)
			(end 0.12065 -0.2794)
			(stroke
				(width 0.1)
				(type default)
			)
			(layer "B.Fab")
		)
		(fp_line
			(start -0.12065 -0.3048)
			(end -0.67945 -0.3048)
			(stroke
				(width 0.1)
				(type default)
			)
			(layer "B.Fab")
		)
		(fp_line
			(start -0.67945 -0.3048)
			(end -0.67945 0.3048)
			(stroke
				(width 0.1)
				(type default)
			)
			(layer "B.Fab")
		)
		(fp_line
			(start 0.12065 -0.2794)
			(end -0.12065 -0.2794)
			(stroke
				(width 0.1)
				(type default)
			)
			(layer "B.Fab")
		)
		(fp_line
			(start -0.12065 -0.2794)
			(end -0.12065 -0.3048)
			(stroke
				(width 0.1)
				(type default)
			)
			(layer "B.Fab")
		)
		(fp_line
			(start 0.12065 0.2794)
			(end 0.12065 0.3048)
			(stroke
				(width 0.1)
				(type default)
			)
			(layer "B.Fab")
		)
		(fp_line
			(start -0.120396 0.2794)
			(end 0.12065 0.2794)
			(stroke
				(width 0.1)
				(type default)
			)
			(layer "B.Fab")
		)
		(fp_line
			(start 0.67945 0.3048)
			(end 0.67945 -0.305054)
			(stroke
				(width 0.1)
				(type default)
			)
			(layer "B.Fab")
		)
		(fp_line
			(start 0.12065 0.3048)
			(end 0.67945 0.3048)
			(stroke
				(width 0.1)
				(type default)
			)
			(layer "B.Fab")
		)
		(fp_line
			(start -0.120396 0.3048)
			(end -0.120396 0.2794)
			(stroke
				(width 0.1)
				(type default)
			)
			(layer "B.Fab")
		)
		(fp_line
			(start -0.67945 0.3048)
			(end -0.120396 0.3048)
			(stroke
				(width 0.1)
				(type default)
			)
			(layer "B.Fab")
		)
		(pad "1" smd circle
			(at 0.40005 0 270)
			(size 0 0)
			(layers "B.Cu" "B.Mask" "B.Paste")
			(net "PWRGD_DRAMPWRGD_CPU0_CD_LVC1_R2")
		)
		(pad "2" smd circle
			(at -0.40005 0 270)
			(size 0 0)
			(layers "B.Cu" "B.Mask" "B.Paste")
			(net "PVCCD_HV_CPU0")
		)
	)
	(footprint ""
		(layer "B.Cu")
		(at 248.943368 -105.256584 -90)
		(property "Reference" "R1484"
			(at 0 0 90)
			(layer "B.SilkS")
			(hide yes)
			(effects
				(font
					(size 1.27 1.27)
				)
				(justify mirror)
			)
		)
		(property "Value" ""
			(at 0 0 90)
			(layer "B.Fab")
			(effects
				(font
					(size 1.27 1.27)
				)
				(justify mirror)
			)
		)
		(duplicate_pad_numbers_are_jumpers no)
		(fp_line
			(start -0.7874 0.4064)
			(end 0.7874 0.4064)
			(stroke
				(width 0.1524)
				(type default)
			)
			(layer "B.SilkS")
		)
		(fp_line
			(start 0.7874 0.4064)
			(end 0.7874 -0.4064)
			(stroke
				(width 0.1524)
				(type default)
			)
			(layer "B.SilkS")
		)
		(fp_line
			(start -0.7874 -0.4064)
			(end -0.7874 0.4064)
			(stroke
				(width 0.1524)
				(type default)
			)
			(layer "B.SilkS")
		)
		(fp_line
			(start 0.7874 -0.4064)
			(end -0.7874 -0.4064)
			(stroke
				(width 0.1524)
				(type default)
			)
			(layer "B.SilkS")
		)
		(fp_line
			(start -0.67945 0.3048)
			(end -0.120396 0.3048)
			(stroke
				(width 0.1)
				(type default)
			)
			(layer "B.Fab")
		)
		(fp_line
			(start -0.120396 0.3048)
			(end -0.120396 0.2794)
			(stroke
				(width 0.1)
				(type default)
			)
			(layer "B.Fab")
		)
		(fp_line
			(start 0.12065 0.3048)
			(end 0.67945 0.3048)
			(stroke
				(width 0.1)
				(type default)
			)
			(layer "B.Fab")
		)
		(fp_line
			(start 0.67945 0.3048)
			(end 0.67945 -0.305054)
			(stroke
				(width 0.1)
				(type default)
			)
			(layer "B.Fab")
		)
		(fp_line
			(start -0.120396 0.2794)
			(end 0.12065 0.2794)
			(stroke
				(width 0.1)
				(type default)
			)
			(layer "B.Fab")
		)
		(fp_line
			(start 0.12065 0.2794)
			(end 0.12065 0.3048)
			(stroke
				(width 0.1)
				(type default)
			)
			(layer "B.Fab")
		)
		(fp_line
			(start -0.12065 -0.2794)
			(end -0.12065 -0.3048)
			(stroke
				(width 0.1)
				(type default)
			)
			(layer "B.Fab")
		)
		(fp_line
			(start 0.12065 -0.2794)
			(end -0.12065 -0.2794)
			(stroke
				(width 0.1)
				(type default)
			)
			(layer "B.Fab")
		)
		(fp_line
			(start -0.67945 -0.3048)
			(end -0.67945 0.3048)
			(stroke
				(width 0.1)
				(type default)
			)
			(layer "B.Fab")
		)
		(fp_line
			(start -0.12065 -0.3048)
			(end -0.67945 -0.3048)
			(stroke
				(width 0.1)
				(type default)
			)
			(layer "B.Fab")
		)
		(fp_line
			(start 0.12065 -0.305054)
			(end 0.12065 -0.2794)
			(stroke
				(width 0.1)
				(type default)
			)
			(layer "B.Fab")
		)
		(fp_line
			(start 0.67945 -0.305054)
			(end 0.12065 -0.305054)
			(stroke
				(width 0.1)
				(type default)
			)
			(layer "B.Fab")
		)
		(pad "1" smd circle
			(at 0.40005 0 90)
			(size 0 0)
			(layers "B.Cu" "B.Mask" "B.Paste")
			(net "FM_CK440Q_DEV_25M_EN")
		)
		(pad "2" smd circle
			(at -0.40005 0 90)
			(size 0 0)
			(layers "B.Cu" "B.Mask" "B.Paste")
			(net "GND")
		)
	)
)
